(kicad_pcb
	(version 20260206)
	(generator "pcbnew")
	(generator_version "10.0")
	(general
		(thickness 1.6)
		(legacy_teardrops no)
	)
	(paper "A4")
	(title_block
		(title "12092022_DA0F0TMDCD0_F0T_Management_Board_D_brd_V3_OCP.brd")
		(comment 1 "Grand Teton / footprints 163-167 of 1440")
	)
	(layers
		(0 "F.Cu" signal "TOP")
		(4 "In1.Cu" signal "GND")
		(6 "In2.Cu" signal "IN1")
		(8 "In3.Cu" signal "GND1")
		(10 "In4.Cu" signal "IN2")
		(12 "In5.Cu" signal "VCC")
		(14 "In6.Cu" signal "VCC1")
		(16 "In7.Cu" signal "IN3")
		(18 "In8.Cu" signal "GND2")
		(20 "In9.Cu" signal "IN4")
		(22 "In10.Cu" signal "GND3")
		(2 "B.Cu" signal "BOTTOM")
		(9 "F.Adhes" user "F.Adhesive")
		(11 "B.Adhes" user "B.Adhesive")
		(13 "F.Paste" user "Package Geometry/Pastemask Top")
		(15 "B.Paste" user "Package Geometry/Pastemask Bottom")
		(5 "F.SilkS" user "Ref Des/Silkscreen Top")
		(7 "B.SilkS" user "Ref Des/Silkscreen Bottom")
		(1 "F.Mask" user "Board Geometry/Soldermask Top")
		(3 "B.Mask" user "Board Geometry/Soldermask Bottom")
		(17 "Dwgs.User" user "User.Drawings")
		(19 "Cmts.User" user "User.Comments")
		(21 "Eco1.User" user "User.Eco1")
		(23 "Eco2.User" user "User.Eco2")
		(25 "Edge.Cuts" user "Board Geometry/Outline")
		(27 "Margin" user)
		(31 "F.CrtYd" user "Package Geometry/Place Bound Top")
		(29 "B.CrtYd" user "Package Geometry/Place Bound Bottom")
		(35 "F.Fab" user "Ref Des/Assembly Top")
		(33 "B.Fab" user "Ref Des/Assembly Bottom")
	)
	(footprint ""
		(layer "F.Cu")
		(at 19.4056 -62.3316 90)
		(property "Reference" "U3"
			(at -1.8288 -1.61163 90)
			(unlocked yes)
			(layer "F.SilkS")
			(effects
				(font
					(size 0.7874 0.5842)
					(thickness 0.1524)
				)
				(justify left)
			)
		)
		(property "Value" ""
			(at 0 0 90)
			(layer "F.Fab")
			(effects
				(font
					(size 1.27 1.27)
				)
			)
		)
		(duplicate_pad_numbers_are_jumpers no)
		(fp_line
			(start 0.8636 -1.050036)
			(end 0.542036 -1.050036)
			(stroke
				(width 0.1524)
				(type default)
			)
			(layer "F.SilkS")
		)
		(fp_line
			(start 0.542036 -1.050036)
			(end 0 -0.508)
			(stroke
				(width 0.1524)
				(type default)
			)
			(layer "F.SilkS")
		)
		(fp_line
			(start -0.542036 -1.050036)
			(end -0.8636 -1.050036)
			(stroke
				(width 0.1524)
				(type default)
			)
			(layer "F.SilkS")
		)
		(fp_line
			(start -0.8636 -1.050036)
			(end -0.8636 1.050036)
			(stroke
				(width 0.1524)
				(type default)
			)
			(layer "F.SilkS")
		)
		(fp_line
			(start 0 -0.508)
			(end -0.542036 -1.050036)
			(stroke
				(width 0.1524)
				(type default)
			)
			(layer "F.SilkS")
		)
		(fp_line
			(start 0.8636 1.050036)
			(end 0.8636 -1.050036)
			(stroke
				(width 0.1524)
				(type default)
			)
			(layer "F.SilkS")
		)
		(fp_line
			(start -0.8636 1.050036)
			(end 0.8636 1.050036)
			(stroke
				(width 0.1524)
				(type default)
			)
			(layer "F.SilkS")
		)
		(fp_poly
			(pts
				(xy -2.201672 -1.857248) (xy -2.919984 -1.138936) (xy -1.842262 -0.77978)
			)
			(stroke
				(width 0)
				(type default)
			)
			(fill yes)
			(layer "F.SilkS")
		)
		(fp_line
			(start 1.199896 -1.050036)
			(end -1.199896 -1.050036)
			(stroke
				(width 0.1)
				(type default)
			)
			(layer "F.Fab")
		)
		(fp_line
			(start -1.199896 -1.050036)
			(end -1.199896 1.050036)
			(stroke
				(width 0.1)
				(type default)
			)
			(layer "F.Fab")
		)
		(fp_line
			(start 1.199896 1.050036)
			(end 1.199896 -1.050036)
			(stroke
				(width 0.1)
				(type default)
			)
			(layer "F.Fab")
		)
		(fp_line
			(start -1.199896 1.050036)
			(end 1.199896 1.050036)
			(stroke
				(width 0.1)
				(type default)
			)
			(layer "F.Fab")
		)
		(fp_poly
			(pts
				(xy -2.794 -1.258062) (xy -2.794 -0.242062) (xy -1.778 -0.750062)
			)
			(stroke
				(width 0)
				(type default)
			)
			(fill yes)
			(layer "F.Fab")
		)
		(pad "1" smd rect
			(at -1.35001 -0.750062)
			(size 0.2794 0.7112)
			(layers "F.Cu" "F.Mask" "F.Paste")
			(net "UART_BIC_DBG_RX")
		)
		(pad "2" smd rect
			(at -1.35001 -0.249936)
			(size 0.2794 0.7112)
			(layers "F.Cu" "F.Mask" "F.Paste")
			(net "UART_BMC_5_RXD_BUF1_SW")
		)
		(pad "3" smd rect
			(at -1.35001 0.249936)
			(size 0.2794 0.7112)
			(layers "F.Cu" "F.Mask" "F.Paste")
			(net "UART_BMC_1_RXD_R")
		)
		(pad "4" smd rect
			(at -1.35001 0.750062)
			(size 0.2794 0.7112)
			(layers "F.Cu" "F.Mask" "F.Paste")
			(net "GND")
		)
		(pad "5" smd rect
			(at 1.35001 0.750062)
			(size 0.2794 0.7112)
			(layers "F.Cu" "F.Mask" "F.Paste")
			(net "FM_UARTSW_LSB_N")
		)
		(pad "6" smd rect
			(at 1.35001 0.249936)
			(size 0.2794 0.7112)
			(layers "F.Cu" "F.Mask" "F.Paste")
			(net "FM_UARTSW_MSB_N")
		)
		(pad "7" smd rect
			(at 1.35001 -0.249936)
			(size 0.2794 0.7112)
			(layers "F.Cu" "F.Mask" "F.Paste")
			(net "SPA_SIN_SW_BUF")
		)
		(pad "8" smd rect
			(at 1.35001 -0.750062)
			(size 0.2794 0.7112)
			(layers "F.Cu" "F.Mask" "F.Paste")
			(net "P3V3_AUX")
		)
	)
	(footprint ""
		(layer "F.Cu")
		(at 30.41904 -70.536054 90)
		(property "Reference" "R651"
			(at 0 0 90)
			(layer "F.SilkS")
			(hide yes)
			(effects
				(font
					(size 1.27 1.27)
				)
			)
		)
		(property "Value" ""
			(at 0 0 90)
			(layer "F.Fab")
			(effects
				(font
					(size 1.27 1.27)
				)
			)
		)
		(duplicate_pad_numbers_are_jumpers no)
		(fp_line
			(start 0.7874 -0.4064)
			(end 0.7874 0.4064)
			(stroke
				(width 0.1524)
				(type default)
			)
			(layer "F.SilkS")
		)
		(fp_line
			(start -0.7874 -0.4064)
			(end 0.7874 -0.4064)
			(stroke
				(width 0.1524)
				(type default)
			)
			(layer "F.SilkS")
		)
		(fp_line
			(start 0.7874 0.4064)
			(end -0.7874 0.4064)
			(stroke
				(width 0.1524)
				(type default)
			)
			(layer "F.SilkS")
		)
		(fp_line
			(start -0.7874 0.4064)
			(end -0.7874 -0.4064)
			(stroke
				(width 0.1524)
				(type default)
			)
			(layer "F.SilkS")
		)
		(fp_line
			(start -0.12065 -0.305054)
			(end -0.12065 -0.2794)
			(stroke
				(width 0.1)
				(type default)
			)
			(layer "F.Fab")
		)
		(fp_line
			(start -0.67945 -0.305054)
			(end -0.12065 -0.305054)
			(stroke
				(width 0.1)
				(type default)
			)
			(layer "F.Fab")
		)
		(fp_line
			(start 0.67945 -0.3048)
			(end 0.67945 0.3048)
			(stroke
				(width 0.1)
				(type default)
			)
			(layer "F.Fab")
		)
		(fp_line
			(start 0.12065 -0.3048)
			(end 0.67945 -0.3048)
			(stroke
				(width 0.1)
				(type default)
			)
			(layer "F.Fab")
		)
		(fp_line
			(start 0.12065 -0.2794)
			(end 0.12065 -0.3048)
			(stroke
				(width 0.1)
				(type default)
			)
			(layer "F.Fab")
		)
		(fp_line
			(start -0.12065 -0.2794)
			(end 0.12065 -0.2794)
			(stroke
				(width 0.1)
				(type default)
			)
			(layer "F.Fab")
		)
		(fp_line
			(start 0.120396 0.2794)
			(end -0.12065 0.2794)
			(stroke
				(width 0.1)
				(type default)
			)
			(layer "F.Fab")
		)
		(fp_line
			(start -0.12065 0.2794)
			(end -0.12065 0.3048)
			(stroke
				(width 0.1)
				(type default)
			)
			(layer "F.Fab")
		)
		(fp_line
			(start 0.67945 0.3048)
			(end 0.120396 0.3048)
			(stroke
				(width 0.1)
				(type default)
			)
			(layer "F.Fab")
		)
		(fp_line
			(start 0.120396 0.3048)
			(end 0.120396 0.2794)
			(stroke
				(width 0.1)
				(type default)
			)
			(layer "F.Fab")
		)
		(fp_line
			(start -0.12065 0.3048)
			(end -0.67945 0.3048)
			(stroke
				(width 0.1)
				(type default)
			)
			(layer "F.Fab")
		)
		(fp_line
			(start -0.67945 0.3048)
			(end -0.67945 -0.305054)
			(stroke
				(width 0.1)
				(type default)
			)
			(layer "F.Fab")
		)
		(pad "1" smd circle
			(at -0.40005 0 90)
			(size 0 0)
			(layers "F.Cu" "F.Mask" "F.Paste")
			(net "BMC_EMMC_DT6")
		)
		(pad "2" smd circle
			(at 0.40005 0 90)
			(size 0 0)
			(layers "F.Cu" "F.Mask" "F.Paste")
			(net "EMMC_DT6_R")
		)
	)
	(footprint ""
		(layer "F.Cu")
		(at 85.7504 -70.4596 -90)
		(property "Reference" "PR275"
			(at 0 0 270)
			(layer "F.SilkS")
			(hide yes)
			(effects
				(font
					(size 1.27 1.27)
				)
			)
		)
		(property "Value" ""
			(at 0 0 270)
			(layer "F.Fab")
			(effects
				(font
					(size 1.27 1.27)
				)
			)
		)
		(duplicate_pad_numbers_are_jumpers no)
		(fp_line
			(start -0.7874 0.4064)
			(end -0.7874 -0.4064)
			(stroke
				(width 0.1524)
				(type default)
			)
			(layer "F.SilkS")
		)
		(fp_line
			(start 0.7874 0.4064)
			(end -0.7874 0.4064)
			(stroke
				(width 0.1524)
				(type default)
			)
			(layer "F.SilkS")
		)
		(fp_line
			(start -0.7874 -0.4064)
			(end 0.7874 -0.4064)
			(stroke
				(width 0.1524)
				(type default)
			)
			(layer "F.SilkS")
		)
		(fp_line
			(start 0.7874 -0.4064)
			(end 0.7874 0.4064)
			(stroke
				(width 0.1524)
				(type default)
			)
			(layer "F.SilkS")
		)
		(fp_line
			(start -0.67945 0.3048)
			(end -0.67945 -0.305054)
			(stroke
				(width 0.1)
				(type default)
			)
			(layer "F.Fab")
		)
		(fp_line
			(start -0.12065 0.3048)
			(end -0.67945 0.3048)
			(stroke
				(width 0.1)
				(type default)
			)
			(layer "F.Fab")
		)
		(fp_line
			(start 0.120396 0.3048)
			(end 0.120396 0.2794)
			(stroke
				(width 0.1)
				(type default)
			)
			(layer "F.Fab")
		)
		(fp_line
			(start 0.67945 0.3048)
			(end 0.120396 0.3048)
			(stroke
				(width 0.1)
				(type default)
			)
			(layer "F.Fab")
		)
		(fp_line
			(start -0.12065 0.2794)
			(end -0.12065 0.3048)
			(stroke
				(width 0.1)
				(type default)
			)
			(layer "F.Fab")
		)
		(fp_line
			(start 0.120396 0.2794)
			(end -0.12065 0.2794)
			(stroke
				(width 0.1)
				(type default)
			)
			(layer "F.Fab")
		)
		(fp_line
			(start -0.12065 -0.2794)
			(end 0.12065 -0.2794)
			(stroke
				(width 0.1)
				(type default)
			)
			(layer "F.Fab")
		)
		(fp_line
			(start 0.12065 -0.2794)
			(end 0.12065 -0.3048)
			(stroke
				(width 0.1)
				(type default)
			)
			(layer "F.Fab")
		)
		(fp_line
			(start 0.12065 -0.3048)
			(end 0.67945 -0.3048)
			(stroke
				(width 0.1)
				(type default)
			)
			(layer "F.Fab")
		)
		(fp_line
			(start 0.67945 -0.3048)
			(end 0.67945 0.3048)
			(stroke
				(width 0.1)
				(type default)
			)
			(layer "F.Fab")
		)
		(fp_line
			(start -0.67945 -0.305054)
			(end -0.12065 -0.305054)
			(stroke
				(width 0.1)
				(type default)
			)
			(layer "F.Fab")
		)
		(fp_line
			(start -0.12065 -0.305054)
			(end -0.12065 -0.2794)
			(stroke
				(width 0.1)
				(type default)
			)
			(layer "F.Fab")
		)
		(pad "1" smd circle
			(at -0.40005 0 270)
			(size 0 0)
			(layers "F.Cu" "F.Mask" "F.Paste")
			(net "P5V_AUX")
		)
		(pad "2" smd circle
			(at 0.40005 0 270)
			(size 0 0)
			(layers "F.Cu" "F.Mask" "F.Paste")
			(net "PVCC1_AUX")
		)
	)
	(footprint ""
		(layer "F.Cu")
		(at 39.932864 -45.384466 180)
		(property "Reference" "R820"
			(at 0 0 180)
			(layer "F.SilkS")
			(hide yes)
			(effects
				(font
					(size 1.27 1.27)
				)
			)
		)
		(property "Value" ""
			(at 0 0 180)
			(layer "F.Fab")
			(effects
				(font
					(size 1.27 1.27)
				)
			)
		)
		(duplicate_pad_numbers_are_jumpers no)
		(fp_line
			(start 0.7874 0.4064)
			(end -0.7874 0.4064)
			(stroke
				(width 0.1524)
				(type default)
			)
			(layer "F.SilkS")
		)
		(fp_line
			(start 0.7874 -0.4064)
			(end 0.7874 0.4064)
			(stroke
				(width 0.1524)
				(type default)
			)
			(layer "F.SilkS")
		)
		(fp_line
			(start -0.7874 0.4064)
			(end -0.7874 -0.4064)
			(stroke
				(width 0.1524)
				(type default)
			)
			(layer "F.SilkS")
		)
		(fp_line
			(start -0.7874 -0.4064)
			(end 0.7874 -0.4064)
			(stroke
				(width 0.1524)
				(type default)
			)
			(layer "F.SilkS")
		)
		(fp_line
			(start 0.67945 0.3048)
			(end 0.120396 0.3048)
			(stroke
				(width 0.1)
				(type default)
			)
			(layer "F.Fab")
		)
		(fp_line
			(start 0.67945 -0.3048)
			(end 0.67945 0.3048)
			(stroke
				(width 0.1)
				(type default)
			)
			(layer "F.Fab")
		)
		(fp_line
			(start 0.12065 -0.2794)
			(end 0.12065 -0.3048)
			(stroke
				(width 0.1)
				(type default)
			)
			(layer "F.Fab")
		)
		(fp_line
			(start 0.12065 -0.3048)
			(end 0.67945 -0.3048)
			(stroke
				(width 0.1)
				(type default)
			)
			(layer "F.Fab")
		)
		(fp_line
			(start 0.120396 0.3048)
			(end 0.120396 0.2794)
			(stroke
				(width 0.1)
				(type default)
			)
			(layer "F.Fab")
		)
		(fp_line
			(start 0.120396 0.2794)
			(end -0.12065 0.2794)
			(stroke
				(width 0.1)
				(type default)
			)
			(layer "F.Fab")
		)
		(fp_line
			(start -0.12065 0.3048)
			(end -0.67945 0.3048)
			(stroke
				(width 0.1)
				(type default)
			)
			(layer "F.Fab")
		)
		(fp_line
			(start -0.12065 0.2794)
			(end -0.12065 0.3048)
			(stroke
				(width 0.1)
				(type default)
			)
			(layer "F.Fab")
		)
		(fp_line
			(start -0.12065 -0.2794)
			(end 0.12065 -0.2794)
			(stroke
				(width 0.1)
				(type default)
			)
			(layer "F.Fab")
		)
		(fp_line
			(start -0.12065 -0.305054)
			(end -0.12065 -0.2794)
			(stroke
				(width 0.1)
				(type default)
			)
			(layer "F.Fab")
		)
		(fp_line
			(start -0.67945 0.3048)
			(end -0.67945 -0.305054)
			(stroke
				(width 0.1)
				(type default)
			)
			(layer "F.Fab")
		)
		(fp_line
			(start -0.67945 -0.305054)
			(end -0.12065 -0.305054)
			(stroke
				(width 0.1)
				(type default)
			)
			(layer "F.Fab")
		)
		(pad "1" smd circle
			(at -0.40005 0 180)
			(size 0 0)
			(layers "F.Cu" "F.Mask" "F.Paste")
			(net "SMB_BMC_MM14_R_SDA")
		)
		(pad "2" smd circle
			(at 0.40005 0 180)
			(size 0 0)
			(layers "F.Cu" "F.Mask" "F.Paste")
			(net "GND")
		)
	)
	(footprint ""
		(layer "F.Cu")
		(at 9.7536 -80.5434)
		(property "Reference" "R108"
			(at 0 0 0)
			(layer "F.SilkS")
			(hide yes)
			(effects
				(font
					(size 1.27 1.27)
				)
			)
		)
		(property "Value" ""
			(at 0 0 0)
			(layer "F.Fab")
			(effects
				(font
					(size 1.27 1.27)
				)
			)
		)
		(duplicate_pad_numbers_are_jumpers no)
		(fp_line
			(start -0.7874 -0.4064)
			(end 0.7874 -0.4064)
			(stroke
				(width 0.1524)
				(type default)
			)
			(layer "F.SilkS")
		)
		(fp_line
			(start -0.7874 0.4064)
			(end -0.7874 -0.4064)
			(stroke
				(width 0.1524)
				(type default)
			)
			(layer "F.SilkS")
		)
		(fp_line
			(start 0.7874 -0.4064)
			(end 0.7874 0.4064)
			(stroke
				(width 0.1524)
				(type default)
			)
			(layer "F.SilkS")
		)
		(fp_line
			(start 0.7874 0.4064)
			(end -0.7874 0.4064)
			(stroke
				(width 0.1524)
				(type default)
			)
			(layer "F.SilkS")
		)
		(fp_line
			(start -0.67945 -0.305054)
			(end -0.12065 -0.305054)
			(stroke
				(width 0.1)
				(type default)
			)
			(layer "F.Fab")
		)
		(fp_line
			(start -0.67945 0.3048)
			(end -0.67945 -0.305054)
			(stroke
				(width 0.1)
				(type default)
			)
			(layer "F.Fab")
		)
		(fp_line
			(start -0.12065 -0.305054)
			(end -0.12065 -0.2794)
			(stroke
				(width 0.1)
				(type default)
			)
			(layer "F.Fab")
		)
		(fp_line
			(start -0.12065 -0.2794)
			(end 0.12065 -0.2794)
			(stroke
				(width 0.1)
				(type default)
			)
			(layer "F.Fab")
		)
		(fp_line
			(start -0.12065 0.2794)
			(end -0.12065 0.3048)
			(stroke
				(width 0.1)
				(type default)
			)
			(layer "F.Fab")
		)
		(fp_line
			(start -0.12065 0.3048)
			(end -0.67945 0.3048)
			(stroke
				(width 0.1)
				(type default)
			)
			(layer "F.Fab")
		)
		(fp_line
			(start 0.120396 0.2794)
			(end -0.12065 0.2794)
			(stroke
				(width 0.1)
				(type default)
			)
			(layer "F.Fab")
		)
		(fp_line
			(start 0.120396 0.3048)
			(end 0.120396 0.2794)
			(stroke
				(width 0.1)
				(type default)
			)
			(layer "F.Fab")
		)
		(fp_line
			(start 0.12065 -0.3048)
			(end 0.67945 -0.3048)
			(stroke
				(width 0.1)
				(type default)
			)
			(layer "F.Fab")
		)
		(fp_line
			(start 0.12065 -0.2794)
			(end 0.12065 -0.3048)
			(stroke
				(width 0.1)
				(type default)
			)
			(layer "F.Fab")
		)
		(fp_line
			(start 0.67945 -0.3048)
			(end 0.67945 0.3048)
			(stroke
				(width 0.1)
				(type default)
			)
			(layer "F.Fab")
		)
		(fp_line
			(start 0.67945 0.3048)
			(end 0.120396 0.3048)
			(stroke
				(width 0.1)
				(type default)
			)
			(layer "F.Fab")
		)
		(pad "1" smd circle
			(at -0.40005 0)
			(size 0 0)
			(layers "F.Cu" "F.Mask" "F.Paste")
			(net "RST_SRST_PLD_BMC_BUF_N")
		)
		(pad "2" smd circle
			(at 0.40005 0)
			(size 0 0)
			(layers "F.Cu" "F.Mask" "F.Paste")
			(net "RST_BMC_SRST_BUF_R_N")
		)
	)
)
